(kicad_sch
	(version 20250114)
	(generator "eeschema")
	(generator_version "9.0")
	(paper "A3")
	(title_block
		(title "usb-c-power-adapter")
		(date "2025-06-24")
		(rev "1.1.2")
		(company "Antmicro")
		(comment 1 "www.antmicro.com")
	)
	(sheet
		(at 133.35 142.24)
		(size 25.4 22.86)
		(exclude_from_sim no)
		(in_bom yes)
		(on_board yes)
		(dnp no)
		(stroke
			(width 0.1524)
			(type solid)
		)
		(fill
			(color 0 0 0 0.0000)
		)
		(property "Sheetname" "DC-DC Converters"
			(at 133.35 141.5284 0)
			(effects
				(font
					(size 1.27 1.27)
				)
				(justify left bottom)
			)
		)
		(property "Sheetfile" "dc-dc_converters.kicad_sch"
			(at 133.35 166.37 0)
			(effects
				(font
					(size 1.27 1.27)
				)
				(justify left top)
			)
		)
		(instances
			(project "usb-c-power-adapter"
				(path ""
					(page "3")
				)
			)
		)
	)
	(sheet
		(at 101.6 142.24)
		(size 25.4 22.86)
		(exclude_from_sim no)
		(in_bom yes)
		(on_board yes)
		(dnp no)
		(stroke
			(width 0.1524)
			(type solid)
		)
		(fill
			(color 0 0 0 0.0000)
		)
		(property "Sheetname" "USB PD"
			(at 101.6 141.5284 0)
			(effects
				(font
					(size 1.27 1.27)
				)
				(justify left bottom)
			)
		)
		(property "Sheetfile" "usb_pd.kicad_sch"
			(at 101.6 166.37 0)
			(effects
				(font
					(size 1.27 1.27)
				)
				(justify left top)
			)
		)
		(instances
			(project "usb-c-power-adapter"
				(path ""
					(page "2")
				)
			)
		)
	)
	(sheet_instances
		(path "/"
			(page "1")
		)
	)
)
